# BASEBOARD_FAB2 (Tioga Pass) — schematic netlist excerpt (pin names and nets, part order shuffled) for the footprints in the layout excerpt that follows; sources: Cadence DE-HDL packaged netlist, KiCad conversion of Wiwynn_Tioga_Pass_MB.brd

C9F4  CAP  22UF 4V 20% X6S  pkg 0805LF  page 238 : A = P1V15_AUX_BMC ; B = GND
R4B10  RES  1.00K 1% CHIP  pkg 0402  page 234 : A = P3V3_STBY ; B = PWRGD_PVPP_KLM_R
C3F2  CAP_A  0.1UF 16V 10% X7R  pkg 0402V  page 104 : A = P3V3 ; B = GND

(kicad_pcb
	(version 20260206)
	(generator "pcbnew")
	(generator_version "10.0")
	(general
		(thickness 1.6)
		(legacy_teardrops no)
	)
	(paper "A4")
	(title_block
		(title "Wiwynn_Tioga_Pass_MB.brd")
		(comment 1 "Tioga Pass / footprints 1089-1091 of 4770")
	)
	(layers
		(0 "F.Cu" signal "TOP")
		(4 "In1.Cu" signal "L2GND")
		(6 "In2.Cu" signal "L3")
		(8 "In3.Cu" signal "L4GND")
		(10 "In4.Cu" signal "L5")
		(12 "In5.Cu" signal "L6GND")
		(14 "In6.Cu" signal "L7VCC")
		(16 "In7.Cu" signal "L8VCC")
		(18 "In8.Cu" signal "L9GND")
		(20 "In9.Cu" signal "L10")
		(22 "In10.Cu" signal "L11GND")
		(24 "In11.Cu" signal "L12")
		(26 "In12.Cu" signal "L13GND")
		(2 "B.Cu" signal "BOTTOM")
		(9 "F.Adhes" user "F.Adhesive")
		(11 "B.Adhes" user "B.Adhesive")
		(13 "F.Paste" user "Package Geometry/Pastemask Top")
		(15 "B.Paste" user "Package Geometry/Pastemask Bottom")
		(5 "F.SilkS" user "Ref Des/Silkscreen Top")
		(7 "B.SilkS" user "Ref Des/Silkscreen Bottom")
		(1 "F.Mask" user "Board Geometry/Soldermask Top")
		(3 "B.Mask" user "Board Geometry/Soldermask Bottom")
		(17 "Dwgs.User" user "User.Drawings")
		(19 "Cmts.User" user "User.Comments")
		(21 "Eco1.User" user "User.Eco1")
		(23 "Eco2.User" user "User.Eco2")
		(25 "Edge.Cuts" user "Board Geometry/Outline")
		(27 "Margin" user)
		(31 "F.CrtYd" user "Package Geometry/Place Bound Top")
		(29 "B.CrtYd" user "Package Geometry/Place Bound Bottom")
		(35 "F.Fab" user "Ref Des/Assembly Top")
		(33 "B.Fab" user "Ref Des/Assembly Bottom")
	)
	(footprint ""
		(layer "F.Cu")
		(at 152.146 -25.908 -90)
		(property "Reference" "C3F2"
			(at 0 0 270)
			(layer "F.SilkS")
			(hide yes)
			(effects
				(font
					(size 1.27 1.27)
				)
			)
		)
		(property "Value" ""
			(at 0 0 270)
			(layer "F.Fab")
			(effects
				(font
					(size 1.27 1.27)
				)
			)
		)
		(duplicate_pad_numbers_are_jumpers no)
		(fp_poly
			(pts
				(xy 0.3048 -0.1016) (xy 0.3048 0.9906) (xy -0.3048 0.9906) (xy -0.3048 -0.1016)
			)
			(stroke
				(width 0)
				(type default)
			)
			(fill no)
			(layer "F.CrtYd")
		)
		(fp_line
			(start -0.3048 0.9906)
			(end 0.3048 0.9906)
			(stroke
				(width 0.1)
				(type default)
			)
			(layer "F.Fab")
		)
		(fp_line
			(start 0.3048 0.9906)
			(end 0.3048 -0.1016)
			(stroke
				(width 0.1)
				(type default)
			)
			(layer "F.Fab")
		)
		(fp_line
			(start -0.3048 -0.1016)
			(end -0.3048 0.9906)
			(stroke
				(width 0.1)
				(type default)
			)
			(layer "F.Fab")
		)
		(fp_line
			(start 0.3048 -0.1016)
			(end -0.3048 -0.1016)
			(stroke
				(width 0.1)
				(type default)
			)
			(layer "F.Fab")
		)
		(pad "1" smd rect
			(at 0 0 270)
			(size 0.508 0.508)
			(layers "F.Cu" "F.Mask" "F.Paste")
			(net "P3V3")
		)
		(pad "2" smd rect
			(at 0 0.889 270)
			(size 0.508 0.508)
			(layers "F.Cu" "F.Mask" "F.Paste")
			(net "GND")
		)
		(zone
			(layer "F.Cu")
			(hatch none 0.5)
			(connect_pads
				(clearance 0)
			)
			(min_thickness 0.25)
			(keepout
				(tracks not_allowed)
				(vias allowed)
				(pads allowed)
				(copperpour not_allowed)
				(footprints allowed)
			)
			(placement
				(enabled no)
				(sheetname "")
			)
			(fill
				(thermal_gap 0.5)
				(thermal_bridge_width 0.5)
				(island_removal_mode 0)
			)
			(polygon
				(pts
					(xy 151.511 -26.162) (xy 151.511 -25.654) (xy 151.892 -25.654) (xy 151.892 -26.162)
				)
			)
		)
		(zone
			(layer "F.Cu")
			(hatch none 0.5)
			(connect_pads
				(clearance 0)
			)
			(min_thickness 0.25)
			(keepout
				(tracks allowed)
				(vias not_allowed)
				(pads allowed)
				(copperpour not_allowed)
				(footprints allowed)
			)
			(placement
				(enabled no)
				(sheetname "")
			)
			(fill
				(thermal_gap 0.5)
				(thermal_bridge_width 0.5)
				(island_removal_mode 0)
			)
			(polygon
				(pts
					(xy 151.892 -26.162) (xy 151.892 -25.654) (xy 151.511 -25.654) (xy 151.511 -26.162)
				)
			)
		)
	)
	(footprint ""
		(layer "F.Cu")
		(at 458.177392 -40.877998 -90)
		(property "Reference" "C9F4"
			(at 0 0 270)
			(layer "F.SilkS")
			(hide yes)
			(effects
				(font
					(size 1.27 1.27)
				)
			)
		)
		(property "Value" ""
			(at 0 0 270)
			(layer "F.Fab")
			(effects
				(font
					(size 1.27 1.27)
				)
			)
		)
		(duplicate_pad_numbers_are_jumpers no)
		(fp_poly
			(pts
				(xy -0.7239 -0.2159) (xy 0.7239 -0.2159) (xy 0.7239 1.9939) (xy -0.7239 1.9939)
			)
			(stroke
				(width 0)
				(type default)
			)
			(fill no)
			(layer "F.CrtYd")
		)
		(fp_line
			(start -0.7239 1.9939)
			(end 0.7239 1.9939)
			(stroke
				(width 0.1)
				(type default)
			)
			(layer "F.Fab")
		)
		(fp_line
			(start 0.7239 1.9939)
			(end 0.7239 -0.2159)
			(stroke
				(width 0.1)
				(type default)
			)
			(layer "F.Fab")
		)
		(fp_line
			(start -0.7239 -0.2159)
			(end -0.7239 1.9939)
			(stroke
				(width 0.1)
				(type default)
			)
			(layer "F.Fab")
		)
		(fp_line
			(start 0.7239 -0.2159)
			(end -0.7239 -0.2159)
			(stroke
				(width 0.1)
				(type default)
			)
			(layer "F.Fab")
		)
		(pad "1" smd rect
			(at 0 0 270)
			(size 1.27 1.016)
			(layers "F.Cu" "F.Mask" "F.Paste")
			(net "P1V15_AUX_BMC")
		)
		(pad "2" smd rect
			(at 0 1.778 270)
			(size 1.27 1.016)
			(layers "F.Cu" "F.Mask" "F.Paste")
			(net "GND")
		)
		(zone
			(layer "F.Cu")
			(hatch none 0.5)
			(connect_pads
				(clearance 0)
			)
			(min_thickness 0.25)
			(keepout
				(tracks not_allowed)
				(vias allowed)
				(pads allowed)
				(copperpour not_allowed)
				(footprints allowed)
			)
			(placement
				(enabled no)
				(sheetname "")
			)
			(fill
				(thermal_gap 0.5)
				(thermal_bridge_width 0.5)
				(island_removal_mode 0)
			)
			(polygon
				(pts
					(xy 457.669392 -41.512998) (xy 457.669392 -40.242998) (xy 456.907392 -40.242998) (xy 456.907392 -41.512998)
				)
			)
		)
	)
	(footprint ""
		(layer "F.Cu")
		(at 179.959 -130.8735 180)
		(property "Reference" "R4B10"
			(at 0 0 180)
			(layer "F.SilkS")
			(hide yes)
			(effects
				(font
					(size 1.27 1.27)
				)
			)
		)
		(property "Value" ""
			(at 0 0 180)
			(layer "F.Fab")
			(effects
				(font
					(size 1.27 1.27)
				)
			)
		)
		(duplicate_pad_numbers_are_jumpers no)
		(fp_poly
			(pts
				(xy -0.2794 -0.1016) (xy 0.2794 -0.1016) (xy 0.2794 0.9906) (xy -0.2794 0.9906)
			)
			(stroke
				(width 0)
				(type default)
			)
			(fill no)
			(layer "F.CrtYd")
		)
		(fp_line
			(start 0.2794 0.9906)
			(end 0.2794 -0.1016)
			(stroke
				(width 0.1)
				(type default)
			)
			(layer "F.Fab")
		)
		(fp_line
			(start 0.2794 -0.1016)
			(end -0.2794 -0.1016)
			(stroke
				(width 0.1)
				(type default)
			)
			(layer "F.Fab")
		)
		(fp_line
			(start -0.2794 0.9906)
			(end 0.2794 0.9906)
			(stroke
				(width 0.1)
				(type default)
			)
			(layer "F.Fab")
		)
		(fp_line
			(start -0.2794 -0.1016)
			(end -0.2794 0.9906)
			(stroke
				(width 0.1)
				(type default)
			)
			(layer "F.Fab")
		)
		(pad "1" smd rect
			(at 0 0 180)
			(size 0.508 0.508)
			(layers "F.Cu" "F.Mask" "F.Paste")
			(net "P3V3_STBY")
		)
		(pad "2" smd rect
			(at 0 0.889 180)
			(size 0.508 0.508)
			(layers "F.Cu" "F.Mask" "F.Paste")
			(net "PWRGD_PVPP_KLM_R")
		)
		(zone
			(layer "F.Cu")
			(hatch none 0.5)
			(connect_pads
				(clearance 0)
			)
			(min_thickness 0.25)
			(keepout
				(tracks not_allowed)
				(vias allowed)
				(pads allowed)
				(copperpour not_allowed)
				(footprints allowed)
			)
			(placement
				(enabled no)
				(sheetname "")
			)
			(fill
				(thermal_gap 0.5)
				(thermal_bridge_width 0.5)
				(island_removal_mode 0)
			)
			(polygon
				(pts
					(xy 180.213 -131.5085) (xy 179.705 -131.5085) (xy 179.705 -131.1275) (xy 180.213 -131.1275)
				)
			)
		)
		(zone
			(layer "F.Cu")
			(hatch none 0.5)
			(connect_pads
				(clearance 0)
			)
			(min_thickness 0.25)
			(keepout
				(tracks allowed)
				(vias not_allowed)
				(pads allowed)
				(copperpour not_allowed)
				(footprints allowed)
			)
			(placement
				(enabled no)
				(sheetname "")
			)
			(fill
				(thermal_gap 0.5)
				(thermal_bridge_width 0.5)
				(island_removal_mode 0)
			)
			(polygon
				(pts
					(xy 180.213 -131.1275) (xy 179.705 -131.1275) (xy 179.705 -131.5085) (xy 180.213 -131.5085)
				)
			)
		)
	)
)
